(kicad_pcb
	(version 20241229)
	(generator "pcbnew")
	(generator_version "9.0")
	(general
		(thickness 1.711)
		(legacy_teardrops no)
	)
	(paper "A4")
	(title_block
		(title "Antmicro Baseboard for Jetson AGX Thor")
		(date "2026-02-18")
		(rev "1.1.0")
		(company "Antmicro Ltd")
		(comment 1 "www.antmicro.com")
		(comment 9 "footprints 164-166 of 1170")
	)
	(layers
		(0 "F.Cu" signal)
		(4 "In1.Cu" signal)
		(6 "In2.Cu" signal)
		(8 "In3.Cu" signal)
		(10 "In4.Cu" jumper)
		(12 "In5.Cu" signal)
		(14 "In6.Cu" signal)
		(16 "In7.Cu" signal)
		(18 "In8.Cu" signal)
		(2 "B.Cu" signal)
		(9 "F.Adhes" user "F.Adhesive")
		(11 "B.Adhes" user "B.Adhesive")
		(13 "F.Paste" user)
		(15 "B.Paste" user)
		(5 "F.SilkS" user "F.Silkscreen")
		(7 "B.SilkS" user "B.Silkscreen")
		(1 "F.Mask" user)
		(3 "B.Mask" user)
		(17 "Dwgs.User" user "User.Drawings")
		(19 "Cmts.User" user "User.Comments")
		(21 "Eco1.User" user "User.Eco1")
		(23 "Eco2.User" user "User.Eco2")
		(25 "Edge.Cuts" user)
		(27 "Margin" user)
		(31 "F.CrtYd" user "F.Courtyard")
		(29 "B.CrtYd" user "B.Courtyard")
		(35 "F.Fab" user)
		(33 "B.Fab" user)
	)
	(footprint "antmicro-footprints:C_0402_1005Metric"
		(layer "F.Cu")
		(at 218.8 132.825 180)
		(descr "Capacitor SMD 0402")
		(tags "capacitor SMD 0402")
		(property "Reference" "C81"
			(at -0.9 2.425 0)
			(layer "F.SilkS")
			(effects
				(font
					(size 0.7 0.7)
					(thickness 0.15)
				)
				(justify right top)
			)
		)
		(property "Value" "C_100n_0402"
			(at -1.022927 2.155213 0)
			(layer "F.Fab")
			(effects
				(font
					(size 0.7 0.7)
					(thickness 0.15)
				)
				(justify right top)
			)
		)
		(property "Datasheet" "https://www.murata.com/products/productdetail?partno=GRM155R61H104KE14%23"
			(at 0 0 0)
			(layer "F.Fab")
			(hide yes)
			(effects
				(font
					(size 1.27 1.27)
					(thickness 0.15)
				)
			)
		)
		(property "Description" "SMD Multilayer Ceramic Capacitor, 0.1 µF, 50 V, 0402 [1005 Metric], ± 10%, X5R, GRM Series"
			(at 0 0 0)
			(layer "F.Fab")
			(hide yes)
			(effects
				(font
					(size 1.27 1.27)
					(thickness 0.15)
				)
			)
		)
		(property "Manufacturer" "Murata"
			(at 0 0 180)
			(unlocked yes)
			(layer "F.Fab")
			(hide yes)
			(effects
				(font
					(size 1 1)
					(thickness 0.15)
				)
			)
		)
		(property "MPN" "GRM155R61H104KE14D"
			(at 0 0 180)
			(unlocked yes)
			(layer "F.Fab")
			(hide yes)
			(effects
				(font
					(size 1 1)
					(thickness 0.15)
				)
			)
		)
		(property "Val" "100n"
			(at 0 0 180)
			(unlocked yes)
			(layer "F.Fab")
			(hide yes)
			(effects
				(font
					(size 1 1)
					(thickness 0.15)
				)
			)
		)
		(property "License" "Apache-2.0"
			(at 0 0 180)
			(unlocked yes)
			(layer "F.Fab")
			(hide yes)
			(effects
				(font
					(size 1 1)
					(thickness 0.15)
				)
			)
		)
		(property "Author" "Antmicro"
			(at 0 0 180)
			(unlocked yes)
			(layer "F.Fab")
			(hide yes)
			(effects
				(font
					(size 1 1)
					(thickness 0.15)
				)
			)
		)
		(property "Voltage" "50V"
			(at 0 0 180)
			(unlocked yes)
			(layer "F.Fab")
			(hide yes)
			(effects
				(font
					(size 1 1)
					(thickness 0.15)
				)
			)
		)
		(property "Dielectric" "X5R"
			(at 0 0 180)
			(unlocked yes)
			(layer "F.Fab")
			(hide yes)
			(effects
				(font
					(size 1 1)
					(thickness 0.15)
				)
			)
		)
		(sheetname "/USB Hub/")
		(sheetfile "usb_hub.kicad_sch")
		(attr smd)
		(fp_rect
			(start -0.925 -0.47)
			(end 0.925 0.47)
			(stroke
				(width 0.05)
				(type default)
			)
			(fill no)
			(layer "F.CrtYd")
		)
		(fp_line
			(start 0.504 0.248)
			(end -0.494 0.248)
			(stroke
				(width 0.15)
				(type solid)
			)
			(layer "F.Fab")
		)
		(fp_line
			(start 0.504 -0.25)
			(end 0.504 0.248)
			(stroke
				(width 0.15)
				(type solid)
			)
			(layer "F.Fab")
		)
		(fp_line
			(start -0.494 0.248)
			(end -0.494 -0.25)
			(stroke
				(width 0.15)
				(type solid)
			)
			(layer "F.Fab")
		)
		(fp_line
			(start -0.494 -0.25)
			(end 0.504 -0.25)
			(stroke
				(width 0.15)
				(type solid)
			)
			(layer "F.Fab")
		)
		(fp_text user "${REFERENCE}"
			(at -0.939 4.599 0)
			(layer "F.Fab")
			(effects
				(font
					(size 0.7 0.7)
					(thickness 0.15)
				)
				(justify right top)
			)
		)
		(fp_text user "License: Apache-2.0"
			(at -0.939 5.799 0)
			(layer "F.Fab")
			(effects
				(font
					(size 0.7 0.7)
					(thickness 0.15)
				)
				(justify right top)
			)
		)
		(fp_text user "Author: Antmicro"
			(at -0.939 3.399 0)
			(layer "F.Fab")
			(effects
				(font
					(size 0.7 0.7)
					(thickness 0.15)
				)
				(justify right top)
			)
		)
		(pad "1" smd roundrect
			(at -0.48 0 180)
			(size 0.59 0.64)
			(layers "F.Cu" "F.Mask" "F.Paste")
			(roundrect_rratio 0.25)
			(net 78 "/USB Hub/USBC4_CONN_TX1_P")
			(pintype "passive")
		)
		(pad "2" smd roundrect
			(at 0.48 0 180)
			(size 0.59 0.64)
			(layers "F.Cu" "F.Mask" "F.Paste")
			(roundrect_rratio 0.25)
			(net 40 "/USB Hub/USBC4_TX_{1}+")
			(pintype "passive")
		)
	)
	(footprint "antmicro-footprints:R_0402_1005Metric"
		(layer "F.Cu")
		(at 136 106.93)
		(descr "Resistor SMD 0402")
		(tags "resistor SMD 0402")
		(property "Reference" "R344"
			(at -1.4 -0.53 0)
			(layer "F.SilkS")
			(effects
				(font
					(size 0.7 0.7)
					(thickness 0.15)
				)
				(justify left bottom)
			)
		)
		(property "Value" "R_0R_0402"
			(at -1.011843 1.772046 0)
			(layer "F.Fab")
			(effects
				(font
					(size 0.7 0.7)
					(thickness 0.15)
				)
				(justify left bottom)
			)
		)
		(property "Datasheet" "https://industrial.panasonic.com/cdbs/www-data/pdf/RDA0000/AOA0000C301.pdf"
			(at 0 0 0)
			(layer "F.Fab")
			(hide yes)
			(effects
				(font
					(size 1.27 1.27)
					(thickness 0.15)
				)
			)
		)
		(property "Description" "SMD Chip Resistor, Jumper, 0 ohm, 100 mW, 0402 [1005 Metric], Thick Film, General Purpose"
			(at 0 0 0)
			(layer "F.Fab")
			(hide yes)
			(effects
				(font
					(size 1.27 1.27)
					(thickness 0.15)
				)
			)
		)
		(property "Manufacturer" "Panasonic"
			(at 0 0 0)
			(unlocked yes)
			(layer "F.Fab")
			(hide yes)
			(effects
				(font
					(size 1 1)
					(thickness 0.15)
				)
			)
		)
		(property "MPN" "ERJ2GE0R00X"
			(at 0 0 0)
			(unlocked yes)
			(layer "F.Fab")
			(hide yes)
			(effects
				(font
					(size 1 1)
					(thickness 0.15)
				)
			)
		)
		(property "Val" "0R"
			(at 0 0 0)
			(unlocked yes)
			(layer "F.Fab")
			(hide yes)
			(effects
				(font
					(size 1 1)
					(thickness 0.15)
				)
			)
		)
		(property "License" "Apache-2.0"
			(at 0 0 0)
			(unlocked yes)
			(layer "F.Fab")
			(hide yes)
			(effects
				(font
					(size 1 1)
					(thickness 0.15)
				)
			)
		)
		(property "Author" "Antmicro"
			(at 0 0 0)
			(unlocked yes)
			(layer "F.Fab")
			(hide yes)
			(effects
				(font
					(size 1 1)
					(thickness 0.15)
				)
			)
		)
		(property "Tolerance" "~"
			(at 0 0 0)
			(unlocked yes)
			(layer "F.Fab")
			(hide yes)
			(effects
				(font
					(size 1 1)
					(thickness 0.15)
				)
			)
		)
		(property "Current" "1A"
			(at 0 0 0)
			(unlocked yes)
			(layer "F.Fab")
			(hide yes)
			(effects
				(font
					(size 1 1)
					(thickness 0.15)
				)
			)
		)
		(sheetname "/Peripherals/")
		(sheetfile "peripherals.kicad_sch")
		(attr smd)
		(fp_poly
			(pts
				(xy -0.925 -0.47) (xy -0.925 0.47) (xy 0.925 0.47) (xy 0.925 -0.47)
			)
			(stroke
				(width 0.05)
				(type default)
			)
			(fill no)
			(layer "F.CrtYd")
		)
		(fp_poly
			(pts
				(xy -0.5 -0.25) (xy -0.5 0.25) (xy 0.5 0.25) (xy 0.5 -0.25)
			)
			(stroke
				(width 0.15)
				(type solid)
			)
			(fill no)
			(layer "F.Fab")
		)
		(fp_text user "Author: Antmicro"
			(at -0.95 4.169 0)
			(layer "F.Fab")
			(effects
				(font
					(size 0.7 0.7)
					(thickness 0.15)
				)
				(justify left bottom)
			)
		)
		(fp_text user "License: Apache-2.0"
			(at -0.949999 5.169 0)
			(layer "F.Fab")
			(effects
				(font
					(size 0.7 0.7)
					(thickness 0.15)
				)
				(justify left bottom)
			)
		)
		(fp_text user "${REFERENCE}"
			(at -0.95 3.168 0)
			(layer "F.Fab")
			(effects
				(font
					(size 0.7 0.7)
					(thickness 0.15)
				)
				(justify left bottom)
			)
		)
		(pad "1" smd roundrect
			(at -0.48 0)
			(size 0.59 0.64)
			(layers "F.Cu" "F.Mask" "F.Paste")
			(roundrect_rratio 0.25)
			(net 2 "+3V3")
			(pintype "passive")
		)
		(pad "2" smd roundrect
			(at 0.48 0)
			(size 0.59 0.64)
			(layers "F.Cu" "F.Mask" "F.Paste")
			(roundrect_rratio 0.25)
			(net 1310 "Net-(U71-~{RESET})")
			(pintype "passive")
		)
	)
	(footprint "antmicro-footprints:C_0805_2012Metric"
		(layer "F.Cu")
		(at 174.365 126.92 90)
		(descr "Capacitor SMD 0805")
		(tags "capacitor SMD 0805")
		(property "Reference" "C43"
			(at 1.52 -5.665 90)
			(layer "F.SilkS")
			(effects
				(font
					(size 0.7 0.7)
					(thickness 0.15)
				)
				(justify left bottom)
			)
		)
		(property "Value" "C_22u_25V_0805"
			(at -2.055717 1.963152 90)
			(layer "F.Fab")
			(effects
				(font
					(size 0.7 0.7)
					(thickness 0.15)
				)
				(justify left bottom)
			)
		)
		(property "Datasheet" "https://product.samsungsem.com/mlcc/CL21A226MAYNNN.do"
			(at 0 0 90)
			(layer "F.Fab")
			(hide yes)
			(effects
				(font
					(size 1.27 1.27)
					(thickness 0.15)
				)
			)
		)
		(property "Description" "SMT Multilayer Ceramic Capacitor, 22uF, +/-20%, 25V, X5R, 0805 [2012 Metric]"
			(at 0 0 90)
			(layer "F.Fab")
			(hide yes)
			(effects
				(font
					(size 1.27 1.27)
					(thickness 0.15)
				)
			)
		)
		(property "MPN" "CL21A226MAYNNNE"
			(at 0 0 90)
			(unlocked yes)
			(layer "F.Fab")
			(hide yes)
			(effects
				(font
					(size 1 1)
					(thickness 0.15)
				)
			)
		)
		(property "Manufacturer" "Samsung Electro-Mechanics"
			(at 0 0 90)
			(unlocked yes)
			(layer "F.Fab")
			(hide yes)
			(effects
				(font
					(size 1 1)
					(thickness 0.15)
				)
			)
		)
		(property "License" "Apache-2.0"
			(at 0 0 90)
			(unlocked yes)
			(layer "F.Fab")
			(hide yes)
			(effects
				(font
					(size 1 1)
					(thickness 0.15)
				)
			)
		)
		(property "Author" "Antmicro"
			(at 0 0 90)
			(unlocked yes)
			(layer "F.Fab")
			(hide yes)
			(effects
				(font
					(size 1 1)
					(thickness 0.15)
				)
			)
		)
		(property "Val" "22u"
			(at 0 0 90)
			(unlocked yes)
			(layer "F.Fab")
			(hide yes)
			(effects
				(font
					(size 1 1)
					(thickness 0.15)
				)
			)
		)
		(property "Voltage" "25V"
			(at 0 0 90)
			(unlocked yes)
			(layer "F.Fab")
			(hide yes)
			(effects
				(font
					(size 1 1)
					(thickness 0.15)
				)
			)
		)
		(property "Dielectric" "X5R"
			(at 0 0 90)
			(unlocked yes)
			(layer "F.Fab")
			(hide yes)
			(effects
				(font
					(size 1 1)
					(thickness 0.15)
				)
			)
		)
		(property "Public" "False"
			(at 0 0 90)
			(unlocked yes)
			(layer "F.Fab")
			(hide yes)
			(effects
				(font
					(size 1 1)
					(thickness 0.15)
				)
			)
		)
		(sheetname "/DCDC/")
		(sheetfile "dcdc.kicad_sch")
		(attr smd)
		(fp_line
			(start -0.3 -0.7)
			(end 0.3 -0.7)
			(stroke
				(width 0.15)
				(type solid)
			)
			(layer "F.SilkS")
		)
		(fp_line
			(start -0.3 0.7)
			(end 0.3 0.7)
			(stroke
				(width 0.15)
				(type solid)
			)
			(layer "F.SilkS")
		)
		(fp_rect
			(start 1.95 -0.9)
			(end -1.95 0.9)
			(stroke
				(width 0.05)
				(type default)
			)
			(fill no)
			(layer "F.CrtYd")
		)
		(fp_rect
			(start -0.95 -0.675)
			(end 0.95 0.675)
			(stroke
				(width 0.15)
				(type solid)
			)
			(fill no)
			(layer "F.Fab")
		)
		(fp_text user "License: Apache-2.0"
			(at -1.9 4.947 90)
			(layer "F.Fab")
			(effects
				(font
					(size 0.7 0.7)
					(thickness 0.15)
				)
				(justify left bottom)
			)
		)
		(fp_text user "Author: Antmicro"
			(at -1.9 5.947 90)
			(layer "F.Fab")
			(effects
				(font
					(size 0.7 0.7)
					(thickness 0.15)
				)
				(justify left bottom)
			)
		)
		(fp_text user "${REFERENCE}"
			(at -1.9 3.947 90)
			(layer "F.Fab")
			(effects
				(font
					(size 0.7 0.7)
					(thickness 0.15)
				)
				(justify left bottom)
			)
		)
		(pad "1" smd roundrect
			(at -1.1 0 90)
			(size 1.2 1.3)
			(layers "F.Cu" "F.Mask" "F.Paste")
			(roundrect_rratio 0.25)
			(net 1 "GND")
			(pintype "passive")
		)
		(pad "2" smd roundrect
			(at 1.1 0 90)
			(size 1.2 1.3)
			(layers "F.Cu" "F.Mask" "F.Paste")
			(roundrect_rratio 0.25)
			(net 13 "VCC")
			(pintype "passive")
		)
	)
)
